(kicad_pcb
	(version 20260206)
	(generator "pcbnew")
	(generator_version "10.0")
	(general
		(thickness 1.6)
		(legacy_teardrops no)
	)
	(paper "A4")
	(title_block
		(title "Bryce Canyon_IOM_IOC_16318-2_OCP.brd")
		(comment 1 "Bryce Canyon / footprints 1209-1218 of 1605")
	)
	(layers
		(0 "F.Cu" signal "TOP")
		(4 "In1.Cu" signal "L2GND")
		(6 "In2.Cu" signal "L3")
		(8 "In3.Cu" signal "L4VCC")
		(10 "In4.Cu" signal "L5VCC")
		(12 "In5.Cu" signal "L6")
		(14 "In6.Cu" signal "L7GND")
		(2 "B.Cu" signal "BOTTOM")
		(9 "F.Adhes" user "F.Adhesive")
		(11 "B.Adhes" user "B.Adhesive")
		(13 "F.Paste" user "Package Geometry/Pastemask Top")
		(15 "B.Paste" user "Package Geometry/Pastemask Bottom")
		(5 "F.SilkS" user "Ref Des/Silkscreen Top")
		(7 "B.SilkS" user "Ref Des/Silkscreen Bottom")
		(1 "F.Mask" user "Board Geometry/Soldermask Top")
		(3 "B.Mask" user "Board Geometry/Soldermask Bottom")
		(17 "Dwgs.User" user "User.Drawings")
		(19 "Cmts.User" user "User.Comments")
		(21 "Eco1.User" user "User.Eco1")
		(23 "Eco2.User" user "User.Eco2")
		(25 "Edge.Cuts" user "Board Geometry/Outline")
		(27 "Margin" user)
		(31 "F.CrtYd" user "Package Geometry/Place Bound Top")
		(29 "B.CrtYd" user "Package Geometry/Place Bound Bottom")
		(35 "F.Fab" user "Ref Des/Assembly Top")
		(33 "B.Fab" user "Ref Des/Assembly Bottom")
	)
	(footprint ""
		(layer "B.Cu")
		(at 55.801514 -141.504416)
		(property "Reference" "TP73"
			(at 0 0 0)
			(layer "B.SilkS")
			(hide yes)
			(effects
				(font
					(size 1.27 1.27)
				)
				(justify mirror)
			)
		)
		(property "Value" "TPAD28-2-GP"
			(at 0.0127 -1.6637 0)
			(unlocked yes)
			(layer "B.Fab")
			(hide yes)
			(effects
				(font
					(size 1.016 1.016)
					(thickness 0.1524)
				)
				(justify mirror)
			)
		)
		(property "Device Type" "TPAD28"
			(at 0.0127 -3.1877 0)
			(unlocked yes)
			(layer "B.Fab")
			(hide yes)
			(effects
				(font
					(size 1.016 1.016)
					(thickness 0.1524)
				)
				(justify mirror)
			)
		)
		(duplicate_pad_numbers_are_jumpers no)
		(fp_poly
			(pts
				(arc
					(start 0.3556 0)
					(mid -0.3556 0)
					(end 0.3556 0)
				)
			)
			(stroke
				(width 0)
				(type default)
			)
			(fill no)
			(layer "B.CrtYd")
		)
		(fp_poly
			(pts
				(arc
					(start 0.6096 0)
					(mid -0.6096 0)
					(end 0.6096 0)
				)
			)
			(stroke
				(width 0)
				(type default)
			)
			(fill no)
			(layer "B.Fab")
		)
		(pad "1" smd circle
			(at 0 0 180)
			(size 0.7112 0.7112)
			(layers "B.Cu" "B.Mask" "B.Paste")
			(net "TP_BMC_GPIOI5")
		)
	)
	(footprint ""
		(layer "B.Cu")
		(at 202.394566 -59.01055)
		(property "Reference" "C455"
			(at 0 0 0)
			(layer "B.SilkS")
			(hide yes)
			(effects
				(font
					(size 1.27 1.27)
				)
				(justify mirror)
			)
		)
		(property "Value" "SCD1U16V2KX-3GP"
			(at -1.1811 -2.7051 0)
			(unlocked yes)
			(layer "B.Fab")
			(hide yes)
			(effects
				(font
					(size 1.016 1.016)
					(thickness 0.1524)
				)
				(justify mirror)
			)
		)
		(property "Device Type" "C402H22"
			(at -1.1811 -4.2291 0)
			(unlocked yes)
			(layer "B.Fab")
			(hide yes)
			(effects
				(font
					(size 1.016 1.016)
					(thickness 0.1524)
				)
				(justify mirror)
			)
		)
		(duplicate_pad_numbers_are_jumpers no)
		(fp_rect
			(start 0.4318 0.9525)
			(end -0.4318 -0.9525)
			(stroke
				(width 0)
				(type default)
			)
			(fill no)
			(layer "B.CrtYd")
		)
		(fp_rect
			(start 0.4318 0.9525)
			(end -0.4318 -0.9525)
			(stroke
				(width 0)
				(type default)
			)
			(fill no)
			(layer "B.Fab")
		)
		(pad "1" smd custom
			(at 0 -0.4445 180)
			(size 0.1524 0.1524)
			(layers "B.Cu" "B.Mask" "B.Paste")
			(net "P1V8")
			(options
				(clearance outline)
				(anchor circle)
			)
			(primitives
				(gr_poly
					(pts
						(arc
							(start 0.3048 0.2032)
							(mid 0.275042 0.275042)
							(end 0.2032 0.3048)
						)
						(arc
							(start -0.2032 0.3048)
							(mid -0.275042 0.275042)
							(end -0.3048 0.2032)
						)
						(arc
							(start -0.3048 -0.2032)
							(mid -0.275042 -0.275042)
							(end -0.2032 -0.3048)
						)
						(arc
							(start 0.2032 -0.3048)
							(mid 0.275042 -0.275042)
							(end 0.3048 -0.2032)
						)
					)
					(width 0)
					(fill yes)
				)
			)
		)
		(pad "2" smd custom
			(at 0 0.4445 180)
			(size 0.1524 0.1524)
			(layers "B.Cu" "B.Mask" "B.Paste")
			(net "GND")
			(options
				(clearance outline)
				(anchor circle)
			)
			(primitives
				(gr_poly
					(pts
						(arc
							(start 0.3048 0.2032)
							(mid 0.275042 0.275042)
							(end 0.2032 0.3048)
						)
						(arc
							(start -0.2032 0.3048)
							(mid -0.275042 0.275042)
							(end -0.3048 0.2032)
						)
						(arc
							(start -0.3048 -0.2032)
							(mid -0.275042 -0.275042)
							(end -0.2032 -0.3048)
						)
						(arc
							(start 0.2032 -0.3048)
							(mid 0.275042 -0.275042)
							(end 0.3048 -0.2032)
						)
					)
					(width 0)
					(fill yes)
				)
			)
		)
	)
	(footprint ""
		(layer "B.Cu")
		(at 60.96 -143.9418 90)
		(property "Reference" "R153"
			(at 0 0 90)
			(layer "B.SilkS")
			(hide yes)
			(effects
				(font
					(size 1.27 1.27)
				)
				(justify mirror)
			)
		)
		(property "Value" "0R2J-2-GP"
			(at -0.064008 -3.993896 90)
			(unlocked yes)
			(layer "B.Fab")
			(hide yes)
			(effects
				(font
					(size 1.016 1.016)
					(thickness 0.1524)
				)
				(justify mirror)
			)
		)
		(property "Device Type" "R402H16"
			(at -0.064008 -5.517896 90)
			(unlocked yes)
			(layer "B.Fab")
			(hide yes)
			(effects
				(font
					(size 1.016 1.016)
					(thickness 0.1524)
				)
				(justify mirror)
			)
		)
		(duplicate_pad_numbers_are_jumpers no)
		(fp_line
			(start 0.508 -0.9398)
			(end 0.508 0.9398)
			(stroke
				(width 0.1524)
				(type default)
			)
			(layer "B.SilkS")
		)
		(fp_line
			(start -0.508 -0.9398)
			(end 0.508 -0.9398)
			(stroke
				(width 0.1524)
				(type default)
			)
			(layer "B.SilkS")
		)
		(fp_rect
			(start 0.508 0.9398)
			(end -0.508 -0.9398)
			(stroke
				(width 0)
				(type default)
			)
			(fill no)
			(layer "B.CrtYd")
		)
		(fp_rect
			(start 0.508 0.9398)
			(end -0.508 -0.9398)
			(stroke
				(width 0)
				(type default)
			)
			(fill no)
			(layer "B.Fab")
		)
		(pad "1" smd custom
			(at 0 -0.4445 270)
			(size 0.1397 0.1397)
			(layers "B.Cu" "B.Mask" "B.Paste")
			(net "BMC_SMB10_DAT")
			(options
				(clearance outline)
				(anchor circle)
			)
			(primitives
				(gr_poly
					(pts
						(arc
							(start -0.1778 0.2794)
							(mid -0.249642 0.249642)
							(end -0.2794 0.1778)
						)
						(arc
							(start -0.2794 -0.1778)
							(mid -0.249642 -0.249642)
							(end -0.1778 -0.2794)
						)
						(arc
							(start 0.1778 -0.2794)
							(mid 0.249642 -0.249642)
							(end 0.2794 -0.1778)
						)
						(arc
							(start 0.2794 0.1778)
							(mid 0.249642 0.249642)
							(end 0.1778 0.2794)
						)
					)
					(width 0)
					(fill yes)
				)
			)
		)
		(pad "2" smd custom
			(at 0 0.4445 270)
			(size 0.1397 0.1397)
			(layers "B.Cu" "B.Mask" "B.Paste")
			(net "I2C_EXP_LOC_SDA_OUT")
			(options
				(clearance outline)
				(anchor circle)
			)
			(primitives
				(gr_poly
					(pts
						(arc
							(start -0.1778 0.2794)
							(mid -0.249642 0.249642)
							(end -0.2794 0.1778)
						)
						(arc
							(start -0.2794 -0.1778)
							(mid -0.249642 -0.249642)
							(end -0.1778 -0.2794)
						)
						(arc
							(start 0.1778 -0.2794)
							(mid 0.249642 -0.249642)
							(end 0.2794 -0.1778)
						)
						(arc
							(start 0.2794 0.1778)
							(mid 0.249642 0.249642)
							(end 0.1778 0.2794)
						)
					)
					(width 0)
					(fill yes)
				)
			)
		)
	)
	(footprint ""
		(layer "B.Cu")
		(at 44.35602 -157.98546 90)
		(property "Reference" "L5"
			(at 0 0 90)
			(layer "B.SilkS")
			(hide yes)
			(effects
				(font
					(size 1.27 1.27)
				)
				(justify mirror)
			)
		)
		(property "Value" "MMZ2012S601ATA1N-GP"
			(at 0 -4.2418 90)
			(unlocked yes)
			(layer "B.Fab")
			(hide yes)
			(effects
				(font
					(size 1.016 1.016)
					(thickness 0.1524)
				)
				(justify mirror)
			)
		)
		(property "Device Type" "L805H42"
			(at 0 -5.7912 90)
			(unlocked yes)
			(layer "B.Fab")
			(hide yes)
			(effects
				(font
					(size 1.016 1.016)
					(thickness 0.1524)
				)
				(justify mirror)
			)
		)
		(duplicate_pad_numbers_are_jumpers no)
		(fp_line
			(start 0.889 -1.7018)
			(end -0.889 -1.7018)
			(stroke
				(width 0.1524)
				(type default)
			)
			(layer "B.SilkS")
		)
		(fp_line
			(start -0.889 -1.7018)
			(end -0.889 1.7018)
			(stroke
				(width 0.1524)
				(type default)
			)
			(layer "B.SilkS")
		)
		(fp_line
			(start 0.889 1.7018)
			(end 0.889 -1.7018)
			(stroke
				(width 0.1524)
				(type default)
			)
			(layer "B.SilkS")
		)
		(fp_line
			(start -0.889 1.7018)
			(end 0.889 1.7018)
			(stroke
				(width 0.1524)
				(type default)
			)
			(layer "B.SilkS")
		)
		(fp_rect
			(start 0.9652 1.778)
			(end -0.9652 -1.778)
			(stroke
				(width 0)
				(type default)
			)
			(fill no)
			(layer "B.CrtYd")
		)
		(fp_rect
			(start 0.9652 1.778)
			(end -0.9652 -1.778)
			(stroke
				(width 0)
				(type default)
			)
			(fill no)
			(layer "B.Fab")
		)
		(pad "1" smd rect
			(at 0 -0.9652 270)
			(size 1.397 1.143)
			(layers "B.Cu" "B.Mask" "B.Paste")
			(net "P1V15_STBY")
		)
		(pad "2" smd rect
			(at 0 0.9652 270)
			(size 1.397 1.143)
			(layers "B.Cu" "B.Mask" "B.Paste")
			(net "V1PLLAV11")
		)
	)
	(footprint ""
		(layer "B.Cu")
		(at 192.405 -50.6222 -90)
		(property "Reference" "C331"
			(at 0 0 90)
			(layer "B.SilkS")
			(hide yes)
			(effects
				(font
					(size 1.27 1.27)
				)
				(justify mirror)
			)
		)
		(property "Value" "SC10U6D3V5KX-4GP"
			(at 0.0762 -6.1214 270)
			(unlocked yes)
			(layer "B.Fab")
			(hide yes)
			(effects
				(font
					(size 1.016 1.016)
					(thickness 0.1524)
				)
				(justify mirror)
			)
		)
		(property "Device Type" "C805H58"
			(at 0.0762 -8.1534 270)
			(unlocked yes)
			(layer "B.Fab")
			(hide yes)
			(effects
				(font
					(size 1.016 1.016)
					(thickness 0.1524)
				)
				(justify mirror)
			)
		)
		(duplicate_pad_numbers_are_jumpers no)
		(fp_line
			(start -0.635 0)
			(end 0.635 0)
			(stroke
				(width 0.508)
				(type default)
			)
			(layer "B.SilkS")
		)
		(fp_rect
			(start 0.9652 1.778)
			(end -0.9652 -1.778)
			(stroke
				(width 0)
				(type default)
			)
			(fill no)
			(layer "B.CrtYd")
		)
		(fp_poly
			(pts
				(xy 0.9652 -1.778) (xy -0.9652 -1.778) (xy -0.9652 1.778) (xy 0.9652 1.778)
			)
			(stroke
				(width 0)
				(type default)
			)
			(fill no)
			(layer "B.Fab")
		)
		(pad "1" smd rect
			(at 0 -0.9652 90)
			(size 1.397 1.143)
			(layers "B.Cu" "B.Mask" "B.Paste")
			(net "HM40ADC_VDDA")
		)
		(pad "2" smd rect
			(at 0 0.9652 90)
			(size 1.397 1.143)
			(layers "B.Cu" "B.Mask" "B.Paste")
			(net "GND")
		)
	)
	(footprint ""
		(layer "B.Cu")
		(at 24.4602 -179.2478 -90)
		(property "Reference" "C179"
			(at 0 0 90)
			(layer "B.SilkS")
			(hide yes)
			(effects
				(font
					(size 1.27 1.27)
				)
				(justify mirror)
			)
		)
		(property "Value" "SC4D7U25V5KX-1-GP"
			(at 0.0762 -6.1214 270)
			(unlocked yes)
			(layer "B.Fab")
			(hide yes)
			(effects
				(font
					(size 1.016 1.016)
					(thickness 0.1524)
				)
				(justify mirror)
			)
		)
		(property "Device Type" "C805H58"
			(at 0.0762 -8.1534 270)
			(unlocked yes)
			(layer "B.Fab")
			(hide yes)
			(effects
				(font
					(size 1.016 1.016)
					(thickness 0.1524)
				)
				(justify mirror)
			)
		)
		(duplicate_pad_numbers_are_jumpers no)
		(fp_line
			(start -0.635 0)
			(end 0.635 0)
			(stroke
				(width 0.508)
				(type default)
			)
			(layer "B.SilkS")
		)
		(fp_rect
			(start 0.9652 1.778)
			(end -0.9652 -1.778)
			(stroke
				(width 0)
				(type default)
			)
			(fill no)
			(layer "B.CrtYd")
		)
		(fp_poly
			(pts
				(xy 0.9652 -1.778) (xy -0.9652 -1.778) (xy -0.9652 1.778) (xy 0.9652 1.778)
			)
			(stroke
				(width 0)
				(type default)
			)
			(fill no)
			(layer "B.Fab")
		)
		(pad "1" smd rect
			(at 0 -0.9652 90)
			(size 1.397 1.143)
			(layers "B.Cu" "B.Mask" "B.Paste")
			(net "P12V_STBY_VDD_PU2")
		)
		(pad "2" smd rect
			(at 0 0.9652 90)
			(size 1.397 1.143)
			(layers "B.Cu" "B.Mask" "B.Paste")
			(net "GND")
		)
	)
	(footprint ""
		(layer "B.Cu")
		(at 91.5162 -142.2654)
		(property "Reference" "R722"
			(at 0 0 0)
			(layer "B.SilkS")
			(hide yes)
			(effects
				(font
					(size 1.27 1.27)
				)
				(justify mirror)
			)
		)
		(property "Value" "10KR2J-3-GP"
			(at -0.064008 -3.993896 0)
			(unlocked yes)
			(layer "B.Fab")
			(hide yes)
			(effects
				(font
					(size 1.016 1.016)
					(thickness 0.1524)
				)
				(justify mirror)
			)
		)
		(property "Device Type" "R402H16"
			(at -0.064008 -5.517896 0)
			(unlocked yes)
			(layer "B.Fab")
			(hide yes)
			(effects
				(font
					(size 1.016 1.016)
					(thickness 0.1524)
				)
				(justify mirror)
			)
		)
		(duplicate_pad_numbers_are_jumpers no)
		(fp_line
			(start -0.508 -0.9398)
			(end 0.508 -0.9398)
			(stroke
				(width 0.1524)
				(type default)
			)
			(layer "B.SilkS")
		)
		(fp_line
			(start 0.508 -0.9398)
			(end 0.508 0.9398)
			(stroke
				(width 0.1524)
				(type default)
			)
			(layer "B.SilkS")
		)
		(fp_rect
			(start 0.508 0.9398)
			(end -0.508 -0.9398)
			(stroke
				(width 0)
				(type default)
			)
			(fill no)
			(layer "B.CrtYd")
		)
		(fp_rect
			(start 0.508 0.9398)
			(end -0.508 -0.9398)
			(stroke
				(width 0)
				(type default)
			)
			(fill no)
			(layer "B.Fab")
		)
		(pad "1" smd custom
			(at 0 -0.4445 180)
			(size 0.1397 0.1397)
			(layers "B.Cu" "B.Mask" "B.Paste")
			(net "DB_PRSNT_BMC_N")
			(options
				(clearance outline)
				(anchor circle)
			)
			(primitives
				(gr_poly
					(pts
						(arc
							(start -0.1778 0.2794)
							(mid -0.249642 0.249642)
							(end -0.2794 0.1778)
						)
						(arc
							(start -0.2794 -0.1778)
							(mid -0.249642 -0.249642)
							(end -0.1778 -0.2794)
						)
						(arc
							(start 0.1778 -0.2794)
							(mid 0.249642 -0.249642)
							(end 0.2794 -0.1778)
						)
						(arc
							(start 0.2794 0.1778)
							(mid 0.249642 0.249642)
							(end 0.1778 0.2794)
						)
					)
					(width 0)
					(fill yes)
				)
			)
		)
		(pad "2" smd custom
			(at 0 0.4445 180)
			(size 0.1397 0.1397)
			(layers "B.Cu" "B.Mask" "B.Paste")
			(net "P3V3_STBY")
			(options
				(clearance outline)
				(anchor circle)
			)
			(primitives
				(gr_poly
					(pts
						(arc
							(start -0.1778 0.2794)
							(mid -0.249642 0.249642)
							(end -0.2794 0.1778)
						)
						(arc
							(start -0.2794 -0.1778)
							(mid -0.249642 -0.249642)
							(end -0.1778 -0.2794)
						)
						(arc
							(start 0.1778 -0.2794)
							(mid 0.249642 -0.249642)
							(end 0.2794 -0.1778)
						)
						(arc
							(start 0.2794 0.1778)
							(mid 0.249642 0.249642)
							(end 0.1778 0.2794)
						)
					)
					(width 0)
					(fill yes)
				)
			)
		)
	)
	(footprint ""
		(layer "B.Cu")
		(at 181.87924 -78.56728)
		(property "Reference" "TP104"
			(at 0 0 0)
			(layer "B.SilkS")
			(hide yes)
			(effects
				(font
					(size 1.27 1.27)
				)
				(justify mirror)
			)
		)
		(property "Value" "TPAD28-2-GP"
			(at 0.0127 -1.6637 0)
			(unlocked yes)
			(layer "B.Fab")
			(hide yes)
			(effects
				(font
					(size 1.016 1.016)
					(thickness 0.1524)
				)
				(justify mirror)
			)
		)
		(property "Device Type" "TPAD28"
			(at 0.0127 -3.1877 0)
			(unlocked yes)
			(layer "B.Fab")
			(hide yes)
			(effects
				(font
					(size 1.016 1.016)
					(thickness 0.1524)
				)
				(justify mirror)
			)
		)
		(duplicate_pad_numbers_are_jumpers no)
		(fp_poly
			(pts
				(arc
					(start 0.3556 0)
					(mid -0.3556 0)
					(end 0.3556 0)
				)
			)
			(stroke
				(width 0)
				(type default)
			)
			(fill no)
			(layer "B.CrtYd")
		)
		(fp_poly
			(pts
				(arc
					(start 0.6096 0)
					(mid -0.6096 0)
					(end 0.6096 0)
				)
			)
			(stroke
				(width 0)
				(type default)
			)
			(fill no)
			(layer "B.Fab")
		)
		(pad "1" smd circle
			(at 0 0 180)
			(size 0.7112 0.7112)
			(layers "B.Cu" "B.Mask" "B.Paste")
			(net "IOC_GPIO_19")
		)
	)
	(footprint ""
		(layer "B.Cu")
		(at 41.69029 -122.367548 -90)
		(property "Reference" "C506"
			(at 0 0 90)
			(layer "B.SilkS")
			(hide yes)
			(effects
				(font
					(size 1.27 1.27)
				)
				(justify mirror)
			)
		)
		(property "Value" "SCD1U16V2KX-3GP"
			(at -1.1811 -2.7051 270)
			(unlocked yes)
			(layer "B.Fab")
			(hide yes)
			(effects
				(font
					(size 1.016 1.016)
					(thickness 0.1524)
				)
				(justify mirror)
			)
		)
		(property "Device Type" "C402H22"
			(at -1.1811 -4.2291 270)
			(unlocked yes)
			(layer "B.Fab")
			(hide yes)
			(effects
				(font
					(size 1.016 1.016)
					(thickness 0.1524)
				)
				(justify mirror)
			)
		)
		(duplicate_pad_numbers_are_jumpers no)
		(fp_rect
			(start 0.4318 0.9525)
			(end -0.4318 -0.9525)
			(stroke
				(width 0)
				(type default)
			)
			(fill no)
			(layer "B.CrtYd")
		)
		(fp_rect
			(start 0.4318 0.9525)
			(end -0.4318 -0.9525)
			(stroke
				(width 0)
				(type default)
			)
			(fill no)
			(layer "B.Fab")
		)
		(pad "1" smd custom
			(at 0 -0.4445 90)
			(size 0.1524 0.1524)
			(layers "B.Cu" "B.Mask" "B.Paste")
			(net "P3V3_STBY")
			(options
				(clearance outline)
				(anchor circle)
			)
			(primitives
				(gr_poly
					(pts
						(arc
							(start 0.3048 0.2032)
							(mid 0.275042 0.275042)
							(end 0.2032 0.3048)
						)
						(arc
							(start -0.2032 0.3048)
							(mid -0.275042 0.275042)
							(end -0.3048 0.2032)
						)
						(arc
							(start -0.3048 -0.2032)
							(mid -0.275042 -0.275042)
							(end -0.2032 -0.3048)
						)
						(arc
							(start 0.2032 -0.3048)
							(mid 0.275042 -0.275042)
							(end 0.3048 -0.2032)
						)
					)
					(width 0)
					(fill yes)
				)
			)
		)
		(pad "2" smd custom
			(at 0 0.4445 90)
			(size 0.1524 0.1524)
			(layers "B.Cu" "B.Mask" "B.Paste")
			(net "GND")
			(options
				(clearance outline)
				(anchor circle)
			)
			(primitives
				(gr_poly
					(pts
						(arc
							(start 0.3048 0.2032)
							(mid 0.275042 0.275042)
							(end 0.2032 0.3048)
						)
						(arc
							(start -0.2032 0.3048)
							(mid -0.275042 0.275042)
							(end -0.3048 0.2032)
						)
						(arc
							(start -0.3048 -0.2032)
							(mid -0.275042 -0.275042)
							(end -0.2032 -0.3048)
						)
						(arc
							(start 0.2032 -0.3048)
							(mid 0.275042 -0.275042)
							(end 0.3048 -0.2032)
						)
					)
					(width 0)
					(fill yes)
				)
			)
		)
	)
	(footprint ""
		(layer "B.Cu")
		(at 203.511404 -92.851224 180)
		(property "Reference" "C357"
			(at 0 0 0)
			(layer "B.SilkS")
			(hide yes)
			(effects
				(font
					(size 1.27 1.27)
				)
				(justify mirror)
			)
		)
		(property "Value" "SC10U6D3V5KX-4GP"
			(at 0.0762 -6.1214 180)
			(unlocked yes)
			(layer "B.Fab")
			(hide yes)
			(effects
				(font
					(size 1.016 1.016)
					(thickness 0.1524)
				)
				(justify mirror)
			)
		)
		(property "Device Type" "C805H58"
			(at 0.0762 -8.1534 180)
			(unlocked yes)
			(layer "B.Fab")
			(hide yes)
			(effects
				(font
					(size 1.016 1.016)
					(thickness 0.1524)
				)
				(justify mirror)
			)
		)
		(duplicate_pad_numbers_are_jumpers no)
		(fp_line
			(start -0.635 0)
			(end 0.635 0)
			(stroke
				(width 0.508)
				(type default)
			)
			(layer "B.SilkS")
		)
		(fp_rect
			(start 0.9652 1.778)
			(end -0.9652 -1.778)
			(stroke
				(width 0)
				(type default)
			)
			(fill no)
			(layer "B.CrtYd")
		)
		(fp_poly
			(pts
				(xy 0.9652 -1.778) (xy -0.9652 -1.778) (xy -0.9652 1.778) (xy 0.9652 1.778)
			)
			(stroke
				(width 0)
				(type default)
			)
			(fill no)
			(layer "B.Fab")
		)
		(pad "1" smd rect
			(at 0 -0.9652)
			(size 1.397 1.143)
			(layers "B.Cu" "B.Mask" "B.Paste")
			(net "PCE_VDDH")
		)
		(pad "2" smd rect
			(at 0 0.9652)
			(size 1.397 1.143)
			(layers "B.Cu" "B.Mask" "B.Paste")
			(net "GND")
		)
	)
)
